# BASEBOARD_FAB2 (Tioga Pass) — schematic netlist excerpt (pin names and nets, part order shuffled) for the footprints in the layout excerpt that follows; sources: Cadence DE-HDL packaged netlist, KiCad conversion of Wiwynn_Tioga_Pass_MB.brd

R1L24  RES  10.0 1% CHIP  pkg 0402  page 155 : A = LED_POSTCODE_3 ; B = LED_POSTCODE_3_R
C5W2  CAP_A  22.0UF 4V 20% X6S  pkg 0603V  page 42 : A = PVCCMCP_CPU0 ; B = GND
R1G26  RES  68.1K 1% EMPTY  pkg 0402  page 224 : A = VR_PVDDQ_GHJ_PH1_OCSET ; B = GND

(kicad_pcb
	(version 20260206)
	(generator "pcbnew")
	(generator_version "10.0")
	(general
		(thickness 1.6)
		(legacy_teardrops no)
	)
	(paper "A4")
	(title_block
		(title "Wiwynn_Tioga_Pass_MB.brd")
		(comment 1 "Tioga Pass / footprints 882-884 of 4770")
	)
	(layers
		(0 "F.Cu" signal "TOP")
		(4 "In1.Cu" signal "L2GND")
		(6 "In2.Cu" signal "L3")
		(8 "In3.Cu" signal "L4GND")
		(10 "In4.Cu" signal "L5")
		(12 "In5.Cu" signal "L6GND")
		(14 "In6.Cu" signal "L7VCC")
		(16 "In7.Cu" signal "L8VCC")
		(18 "In8.Cu" signal "L9GND")
		(20 "In9.Cu" signal "L10")
		(22 "In10.Cu" signal "L11GND")
		(24 "In11.Cu" signal "L12")
		(26 "In12.Cu" signal "L13GND")
		(2 "B.Cu" signal "BOTTOM")
		(9 "F.Adhes" user "F.Adhesive")
		(11 "B.Adhes" user "B.Adhesive")
		(13 "F.Paste" user "Package Geometry/Pastemask Top")
		(15 "B.Paste" user "Package Geometry/Pastemask Bottom")
		(5 "F.SilkS" user "Ref Des/Silkscreen Top")
		(7 "B.SilkS" user "Ref Des/Silkscreen Bottom")
		(1 "F.Mask" user "Board Geometry/Soldermask Top")
		(3 "B.Mask" user "Board Geometry/Soldermask Bottom")
		(17 "Dwgs.User" user "User.Drawings")
		(19 "Cmts.User" user "User.Comments")
		(21 "Eco1.User" user "User.Eco1")
		(23 "Eco2.User" user "User.Eco2")
		(25 "Edge.Cuts" user "Board Geometry/Outline")
		(27 "Margin" user)
		(31 "F.CrtYd" user "Package Geometry/Place Bound Top")
		(29 "B.CrtYd" user "Package Geometry/Place Bound Bottom")
		(35 "F.Fab" user "Ref Des/Assembly Top")
		(33 "B.Fab" user "Ref Des/Assembly Bottom")
	)
	(footprint ""
		(layer "F.Cu")
		(at 271.9832 -79.6036 180)
		(property "Reference" "C5W2"
			(at 0.97536 0.76708 90)
			(unlocked yes)
			(layer "F.SilkS")
			(effects
				(font
					(size 0.4064 0.254)
					(thickness 0.1524)
				)
			)
		)
		(property "Value" ""
			(at 0 0 180)
			(layer "F.Fab")
			(effects
				(font
					(size 1.27 1.27)
				)
			)
		)
		(duplicate_pad_numbers_are_jumpers no)
		(fp_poly
			(pts
				(xy -0.4953 -0.2032) (xy 0.4953 -0.2032) (xy 0.4953 1.6002) (xy -0.4953 1.6002)
			)
			(stroke
				(width 0)
				(type default)
			)
			(fill no)
			(layer "F.CrtYd")
		)
		(fp_line
			(start 0.4953 1.6002)
			(end -0.4953 1.6002)
			(stroke
				(width 0.1)
				(type default)
			)
			(layer "F.Fab")
		)
		(fp_line
			(start 0.4953 -0.2032)
			(end 0.4953 1.6002)
			(stroke
				(width 0.1)
				(type default)
			)
			(layer "F.Fab")
		)
		(fp_line
			(start -0.4953 1.6002)
			(end -0.4953 -0.2032)
			(stroke
				(width 0.1)
				(type default)
			)
			(layer "F.Fab")
		)
		(fp_line
			(start -0.4953 -0.2032)
			(end 0.4953 -0.2032)
			(stroke
				(width 0.1)
				(type default)
			)
			(layer "F.Fab")
		)
		(pad "1" smd rect
			(at 0 0 180)
			(size 0.762 0.889)
			(layers "F.Cu" "F.Mask" "F.Paste")
			(net "PVCCMCP_CPU0")
		)
		(pad "2" smd rect
			(at 0 1.397 180)
			(size 0.762 0.889)
			(layers "F.Cu" "F.Mask" "F.Paste")
			(net "GND")
		)
		(zone
			(layer "F.Cu")
			(hatch none 0.5)
			(connect_pads
				(clearance 0)
			)
			(min_thickness 0.25)
			(keepout
				(tracks not_allowed)
				(vias allowed)
				(pads allowed)
				(copperpour not_allowed)
				(footprints allowed)
			)
			(placement
				(enabled no)
				(sheetname "")
			)
			(fill
				(thermal_gap 0.5)
				(thermal_bridge_width 0.5)
				(island_removal_mode 0)
			)
			(polygon
				(pts
					(xy 272.3642 -80.0481) (xy 271.6022 -80.0481) (xy 271.6022 -80.5561) (xy 272.3642 -80.5561)
				)
			)
		)
	)
	(footprint ""
		(layer "F.Cu")
		(at -0.342138 -6.936486)
		(property "Reference" "R1G26"
			(at 0 0 0)
			(layer "F.SilkS")
			(hide yes)
			(effects
				(font
					(size 1.27 1.27)
				)
			)
		)
		(property "Value" ""
			(at 0 0 0)
			(layer "F.Fab")
			(effects
				(font
					(size 1.27 1.27)
				)
			)
		)
		(duplicate_pad_numbers_are_jumpers no)
		(fp_poly
			(pts
				(xy -0.2794 -0.1016) (xy 0.2794 -0.1016) (xy 0.2794 0.9906) (xy -0.2794 0.9906)
			)
			(stroke
				(width 0)
				(type default)
			)
			(fill no)
			(layer "F.CrtYd")
		)
		(fp_line
			(start -0.2794 -0.1016)
			(end -0.2794 0.9906)
			(stroke
				(width 0.1)
				(type default)
			)
			(layer "F.Fab")
		)
		(fp_line
			(start -0.2794 0.9906)
			(end 0.2794 0.9906)
			(stroke
				(width 0.1)
				(type default)
			)
			(layer "F.Fab")
		)
		(fp_line
			(start 0.2794 -0.1016)
			(end -0.2794 -0.1016)
			(stroke
				(width 0.1)
				(type default)
			)
			(layer "F.Fab")
		)
		(fp_line
			(start 0.2794 0.9906)
			(end 0.2794 -0.1016)
			(stroke
				(width 0.1)
				(type default)
			)
			(layer "F.Fab")
		)
		(pad "1" smd rect
			(at 0 0)
			(size 0.508 0.508)
			(layers "F.Cu" "F.Mask" "F.Paste")
			(net "VR_PVDDQ_GHJ_PH1_OCSET")
		)
		(pad "2" smd rect
			(at 0 0.889)
			(size 0.508 0.508)
			(layers "F.Cu" "F.Mask" "F.Paste")
			(net "GND")
		)
		(zone
			(layer "F.Cu")
			(hatch none 0.5)
			(connect_pads
				(clearance 0)
			)
			(min_thickness 0.25)
			(keepout
				(tracks allowed)
				(vias not_allowed)
				(pads allowed)
				(copperpour not_allowed)
				(footprints allowed)
			)
			(placement
				(enabled no)
				(sheetname "")
			)
			(fill
				(thermal_gap 0.5)
				(thermal_bridge_width 0.5)
				(island_removal_mode 0)
			)
			(polygon
				(pts
					(xy -0.596138 -6.682486) (xy -0.088138 -6.682486) (xy -0.088138 -6.301486) (xy -0.596138 -6.301486)
				)
			)
		)
		(zone
			(layer "F.Cu")
			(hatch none 0.5)
			(connect_pads
				(clearance 0)
			)
			(min_thickness 0.25)
			(keepout
				(tracks not_allowed)
				(vias allowed)
				(pads allowed)
				(copperpour not_allowed)
				(footprints allowed)
			)
			(placement
				(enabled no)
				(sheetname "")
			)
			(fill
				(thermal_gap 0.5)
				(thermal_bridge_width 0.5)
				(island_removal_mode 0)
			)
			(polygon
				(pts
					(xy -0.596138 -6.301486) (xy -0.088138 -6.301486) (xy -0.088138 -6.682486) (xy -0.596138 -6.682486)
				)
			)
		)
	)
	(footprint ""
		(layer "F.Cu")
		(at 489.3945 -144.638268 90)
		(property "Reference" "R1L24"
			(at 0 0 90)
			(layer "F.SilkS")
			(hide yes)
			(effects
				(font
					(size 1.27 1.27)
				)
			)
		)
		(property "Value" ""
			(at 0 0 90)
			(layer "F.Fab")
			(effects
				(font
					(size 1.27 1.27)
				)
			)
		)
		(duplicate_pad_numbers_are_jumpers no)
		(fp_poly
			(pts
				(xy -0.2794 -0.1016) (xy 0.2794 -0.1016) (xy 0.2794 0.9906) (xy -0.2794 0.9906)
			)
			(stroke
				(width 0)
				(type default)
			)
			(fill no)
			(layer "F.CrtYd")
		)
		(fp_line
			(start 0.2794 -0.1016)
			(end -0.2794 -0.1016)
			(stroke
				(width 0.1)
				(type default)
			)
			(layer "F.Fab")
		)
		(fp_line
			(start -0.2794 -0.1016)
			(end -0.2794 0.9906)
			(stroke
				(width 0.1)
				(type default)
			)
			(layer "F.Fab")
		)
		(fp_line
			(start 0.2794 0.9906)
			(end 0.2794 -0.1016)
			(stroke
				(width 0.1)
				(type default)
			)
			(layer "F.Fab")
		)
		(fp_line
			(start -0.2794 0.9906)
			(end 0.2794 0.9906)
			(stroke
				(width 0.1)
				(type default)
			)
			(layer "F.Fab")
		)
		(pad "1" smd rect
			(at 0 0 90)
			(size 0.508 0.508)
			(layers "F.Cu" "F.Mask" "F.Paste")
			(net "LED_POSTCODE_3")
		)
		(pad "2" smd rect
			(at 0 0.889 90)
			(size 0.508 0.508)
			(layers "F.Cu" "F.Mask" "F.Paste")
			(net "LED_POSTCODE_3_R")
		)
		(zone
			(layer "F.Cu")
			(hatch none 0.5)
			(connect_pads
				(clearance 0)
			)
			(min_thickness 0.25)
			(keepout
				(tracks allowed)
				(vias not_allowed)
				(pads allowed)
				(copperpour not_allowed)
				(footprints allowed)
			)
			(placement
				(enabled no)
				(sheetname "")
			)
			(fill
				(thermal_gap 0.5)
				(thermal_bridge_width 0.5)
				(island_removal_mode 0)
			)
			(polygon
				(pts
					(xy 489.6485 -144.384268) (xy 489.6485 -144.892268) (xy 490.0295 -144.892268) (xy 490.0295 -144.384268)
				)
			)
		)
		(zone
			(layer "F.Cu")
			(hatch none 0.5)
			(connect_pads
				(clearance 0)
			)
			(min_thickness 0.25)
			(keepout
				(tracks not_allowed)
				(vias allowed)
				(pads allowed)
				(copperpour not_allowed)
				(footprints allowed)
			)
			(placement
				(enabled no)
				(sheetname "")
			)
			(fill
				(thermal_gap 0.5)
				(thermal_bridge_width 0.5)
				(island_removal_mode 0)
			)
			(polygon
				(pts
					(xy 490.0295 -144.384268) (xy 490.0295 -144.892268) (xy 489.6485 -144.892268) (xy 489.6485 -144.384268)
				)
			)
		)
	)
)
